(kicad_pcb
	(version 20260206)
	(generator "pcbnew")
	(generator_version "10.0")
	(general
		(thickness 1.6)
		(legacy_teardrops no)
	)
	(paper "A4")
	(title_block
		(title "fcb — Lightning_FCB_BRD.brd")
		(comment 1 "Lightning (Wiwynn / Facebook NVMe JBOF) / footprints 217-217 of 495")
	)
	(layers
		(0 "F.Cu" signal "TOP")
		(4 "In1.Cu" signal "L2GND")
		(6 "In2.Cu" signal "L3VCC")
		(2 "B.Cu" signal "BOTTOM")
		(9 "F.Adhes" user "F.Adhesive")
		(11 "B.Adhes" user "B.Adhesive")
		(13 "F.Paste" user "Package Geometry/Pastemask Top")
		(15 "B.Paste" user "Package Geometry/Pastemask Bottom")
		(5 "F.SilkS" user "Ref Des/Silkscreen Top")
		(7 "B.SilkS" user "Ref Des/Silkscreen Bottom")
		(1 "F.Mask" user "Board Geometry/Soldermask Top")
		(3 "B.Mask" user "Board Geometry/Soldermask Bottom")
		(17 "Dwgs.User" user "User.Drawings")
		(19 "Cmts.User" user "User.Comments")
		(21 "Eco1.User" user "User.Eco1")
		(23 "Eco2.User" user "User.Eco2")
		(25 "Edge.Cuts" user "Board Geometry/Outline")
		(27 "Margin" user)
		(31 "F.CrtYd" user "Package Geometry/Place Bound Top")
		(29 "B.CrtYd" user "Package Geometry/Place Bound Bottom")
		(35 "F.Fab" user "Ref Des/Assembly Top")
		(33 "B.Fab" user "Ref Des/Assembly Bottom")
	)
	(footprint ""
		(layer "F.Cu")
		(at 43.7134 -138.5062)
		(property "Reference" "PC95"
			(at 0 0 0)
			(layer "F.SilkS")
			(hide yes)
			(effects
				(font
					(size 1.27 1.27)
				)
			)
		)
		(property "Value" "SC10U25V5KX-GP"
			(at -0.0762 -6.1214 0)
			(unlocked yes)
			(layer "F.Fab")
			(hide yes)
			(effects
				(font
					(size 1.016 1.016)
					(thickness 0.1524)
				)
			)
		)
		(property "Device Type" "C805H56"
			(at -0.0762 -8.1534 0)
			(unlocked yes)
			(layer "F.Fab")
			(hide yes)
			(effects
				(font
					(size 1.016 1.016)
					(thickness 0.1524)
				)
			)
		)
		(duplicate_pad_numbers_are_jumpers no)
		(fp_line
			(start 0.635 0)
			(end -0.635 0)
			(stroke
				(width 0.508)
				(type default)
			)
			(layer "F.SilkS")
		)
		(fp_rect
			(start -0.9652 1.778)
			(end 0.9652 -1.778)
			(stroke
				(width 0)
				(type default)
			)
			(fill no)
			(layer "F.CrtYd")
		)
		(fp_poly
			(pts
				(xy -0.9652 -1.778) (xy 0.9652 -1.778) (xy 0.9652 1.778) (xy -0.9652 1.778)
			)
			(stroke
				(width 0)
				(type default)
			)
			(fill no)
			(layer "F.Fab")
		)
		(pad "1" smd rect
			(at 0 -0.9652)
			(size 1.397 1.143)
			(layers "F.Cu" "F.Mask" "F.Paste")
			(net "P12VL_2490_EN_2")
		)
		(pad "2" smd rect
			(at 0 0.9652)
			(size 1.397 1.143)
			(layers "F.Cu" "F.Mask" "F.Paste")
			(net "GND")
		)
	)
)
